# S9S_MB_2U (Grand Teton) — schematic netlist excerpt (pin names and nets, part order shuffled) for the footprints in the layout excerpt that follows; sources: Cadence DE-HDL packaged netlist, KiCad conversion of 03242023_DA0F0TMBIJ0_F0T_Motherboard_J_brd_V01_OCP.brd

ME20  ME_DUMMY_SYMBOL  PB-E1_SMALL EMPTY  pkg PB-E1_SMALL  page 312
PR396  Q_RES  0 5% EMPTY  pkg 0402LF  page 263 : A = P5V_AUX ; B = PVCC1_AUX
R1273  Q_RES  22 1% CHIP  pkg 0402LF  page 209 : A = CLK_100M_OCP_SFF_2_R_DP ; B = CLK_100M_OCP_SFF_2_DP

(kicad_pcb
	(version 20260206)
	(generator "pcbnew")
	(generator_version "10.0")
	(general
		(thickness 1.6)
		(legacy_teardrops no)
	)
	(paper "A4")
	(title_block
		(title "03242023_DA0F0TMBIJ0_F0T_Motherboard_J_brd_V01_OCP.brd")
		(comment 1 "Grand Teton / footprints 2964-2966 of 6105")
	)
	(layers
		(0 "F.Cu" signal "TOP")
		(4 "In1.Cu" signal "GND")
		(6 "In2.Cu" signal "IN1")
		(8 "In3.Cu" signal "GND1")
		(10 "In4.Cu" signal "IN2")
		(12 "In5.Cu" signal "GND2")
		(14 "In6.Cu" signal "IN3")
		(16 "In7.Cu" signal "GND3")
		(18 "In8.Cu" signal "VCC")
		(20 "In9.Cu" signal "VCC1")
		(22 "In10.Cu" signal "GND4")
		(24 "In11.Cu" signal "IN4")
		(26 "In12.Cu" signal "GND5")
		(28 "In13.Cu" signal "IN5")
		(30 "In14.Cu" signal "GND6")
		(32 "In15.Cu" signal "IN6")
		(34 "In16.Cu" signal "GND7")
		(2 "B.Cu" signal "BOTTOM")
		(9 "F.Adhes" user "F.Adhesive")
		(11 "B.Adhes" user "B.Adhesive")
		(13 "F.Paste" user "Package Geometry/Pastemask Top")
		(15 "B.Paste" user "Package Geometry/Pastemask Bottom")
		(5 "F.SilkS" user "Ref Des/Silkscreen Top")
		(7 "B.SilkS" user "Ref Des/Silkscreen Bottom")
		(1 "F.Mask" user "Board Geometry/Soldermask Top")
		(3 "B.Mask" user "Board Geometry/Soldermask Bottom")
		(17 "Dwgs.User" user "User.Drawings")
		(19 "Cmts.User" user "User.Comments")
		(21 "Eco1.User" user "User.Eco1")
		(23 "Eco2.User" user "User.Eco2")
		(25 "Edge.Cuts" user "Board Geometry/Outline")
		(27 "Margin" user)
		(31 "F.CrtYd" user "Package Geometry/Place Bound Top")
		(29 "B.CrtYd" user "Package Geometry/Place Bound Bottom")
		(35 "F.Fab" user "Ref Des/Assembly Top")
		(33 "B.Fab" user "Ref Des/Assembly Bottom")
	)
	(footprint ""
		(layer "F.Cu")
		(at 380.341886 -71.126858)
		(property "Reference" "PR396"
			(at 0 0 0)
			(layer "F.SilkS")
			(hide yes)
			(effects
				(font
					(size 1.27 1.27)
				)
			)
		)
		(property "Value" ""
			(at 0 0 0)
			(layer "F.Fab")
			(effects
				(font
					(size 1.27 1.27)
				)
			)
		)
		(duplicate_pad_numbers_are_jumpers no)
		(fp_line
			(start -0.7874 -0.4064)
			(end 0.7874 -0.4064)
			(stroke
				(width 0.1524)
				(type default)
			)
			(layer "F.SilkS")
		)
		(fp_line
			(start -0.7874 0.4064)
			(end -0.7874 -0.4064)
			(stroke
				(width 0.1524)
				(type default)
			)
			(layer "F.SilkS")
		)
		(fp_line
			(start 0.7874 -0.4064)
			(end 0.7874 0.4064)
			(stroke
				(width 0.1524)
				(type default)
			)
			(layer "F.SilkS")
		)
		(fp_line
			(start 0.7874 0.4064)
			(end -0.7874 0.4064)
			(stroke
				(width 0.1524)
				(type default)
			)
			(layer "F.SilkS")
		)
		(fp_line
			(start -0.67945 -0.305054)
			(end -0.12065 -0.305054)
			(stroke
				(width 0.1)
				(type default)
			)
			(layer "F.Fab")
		)
		(fp_line
			(start -0.67945 0.3048)
			(end -0.67945 -0.305054)
			(stroke
				(width 0.1)
				(type default)
			)
			(layer "F.Fab")
		)
		(fp_line
			(start -0.12065 -0.305054)
			(end -0.12065 -0.2794)
			(stroke
				(width 0.1)
				(type default)
			)
			(layer "F.Fab")
		)
		(fp_line
			(start -0.12065 -0.2794)
			(end 0.12065 -0.2794)
			(stroke
				(width 0.1)
				(type default)
			)
			(layer "F.Fab")
		)
		(fp_line
			(start -0.12065 0.2794)
			(end -0.12065 0.3048)
			(stroke
				(width 0.1)
				(type default)
			)
			(layer "F.Fab")
		)
		(fp_line
			(start -0.12065 0.3048)
			(end -0.67945 0.3048)
			(stroke
				(width 0.1)
				(type default)
			)
			(layer "F.Fab")
		)
		(fp_line
			(start 0.120396 0.2794)
			(end -0.12065 0.2794)
			(stroke
				(width 0.1)
				(type default)
			)
			(layer "F.Fab")
		)
		(fp_line
			(start 0.120396 0.3048)
			(end 0.120396 0.2794)
			(stroke
				(width 0.1)
				(type default)
			)
			(layer "F.Fab")
		)
		(fp_line
			(start 0.12065 -0.3048)
			(end 0.67945 -0.3048)
			(stroke
				(width 0.1)
				(type default)
			)
			(layer "F.Fab")
		)
		(fp_line
			(start 0.12065 -0.2794)
			(end 0.12065 -0.3048)
			(stroke
				(width 0.1)
				(type default)
			)
			(layer "F.Fab")
		)
		(fp_line
			(start 0.67945 -0.3048)
			(end 0.67945 0.3048)
			(stroke
				(width 0.1)
				(type default)
			)
			(layer "F.Fab")
		)
		(fp_line
			(start 0.67945 0.3048)
			(end 0.120396 0.3048)
			(stroke
				(width 0.1)
				(type default)
			)
			(layer "F.Fab")
		)
		(pad "1" smd circle
			(at -0.40005 0)
			(size 0 0)
			(layers "F.Cu" "F.Mask" "F.Paste")
			(net "P5V_AUX")
		)
		(pad "2" smd circle
			(at 0.40005 0)
			(size 0 0)
			(layers "F.Cu" "F.Mask" "F.Paste")
			(net "PVCC1_AUX")
		)
	)
	(footprint ""
		(layer "F.Cu")
		(at 228.816662 -123.167902 180)
		(property "Reference" "R1273"
			(at 0 0 180)
			(layer "F.SilkS")
			(hide yes)
			(effects
				(font
					(size 1.27 1.27)
				)
			)
		)
		(property "Value" ""
			(at 0 0 180)
			(layer "F.Fab")
			(effects
				(font
					(size 1.27 1.27)
				)
			)
		)
		(duplicate_pad_numbers_are_jumpers no)
		(fp_line
			(start 0.7874 0.4064)
			(end -0.7874 0.4064)
			(stroke
				(width 0.1524)
				(type default)
			)
			(layer "F.SilkS")
		)
		(fp_line
			(start 0.7874 -0.087122)
			(end 0.7874 0.4064)
			(stroke
				(width 0.1524)
				(type default)
			)
			(layer "F.SilkS")
		)
		(fp_line
			(start -0.507238 -0.4064)
			(end 0.610362 -0.4064)
			(stroke
				(width 0.1524)
				(type default)
			)
			(layer "F.SilkS")
		)
		(fp_line
			(start -0.7874 0.4064)
			(end -0.7874 0.011938)
			(stroke
				(width 0.1524)
				(type default)
			)
			(layer "F.SilkS")
		)
		(fp_line
			(start 0.67945 0.3048)
			(end 0.120396 0.3048)
			(stroke
				(width 0.1)
				(type default)
			)
			(layer "F.Fab")
		)
		(fp_line
			(start 0.67945 -0.3048)
			(end 0.67945 0.3048)
			(stroke
				(width 0.1)
				(type default)
			)
			(layer "F.Fab")
		)
		(fp_line
			(start 0.12065 -0.2794)
			(end 0.12065 -0.3048)
			(stroke
				(width 0.1)
				(type default)
			)
			(layer "F.Fab")
		)
		(fp_line
			(start 0.12065 -0.3048)
			(end 0.67945 -0.3048)
			(stroke
				(width 0.1)
				(type default)
			)
			(layer "F.Fab")
		)
		(fp_line
			(start 0.120396 0.3048)
			(end 0.120396 0.2794)
			(stroke
				(width 0.1)
				(type default)
			)
			(layer "F.Fab")
		)
		(fp_line
			(start 0.120396 0.2794)
			(end -0.12065 0.2794)
			(stroke
				(width 0.1)
				(type default)
			)
			(layer "F.Fab")
		)
		(fp_line
			(start -0.12065 0.3048)
			(end -0.67945 0.3048)
			(stroke
				(width 0.1)
				(type default)
			)
			(layer "F.Fab")
		)
		(fp_line
			(start -0.12065 0.2794)
			(end -0.12065 0.3048)
			(stroke
				(width 0.1)
				(type default)
			)
			(layer "F.Fab")
		)
		(fp_line
			(start -0.12065 -0.2794)
			(end 0.12065 -0.2794)
			(stroke
				(width 0.1)
				(type default)
			)
			(layer "F.Fab")
		)
		(fp_line
			(start -0.12065 -0.305054)
			(end -0.12065 -0.2794)
			(stroke
				(width 0.1)
				(type default)
			)
			(layer "F.Fab")
		)
		(fp_line
			(start -0.67945 0.3048)
			(end -0.67945 -0.305054)
			(stroke
				(width 0.1)
				(type default)
			)
			(layer "F.Fab")
		)
		(fp_line
			(start -0.67945 -0.305054)
			(end -0.12065 -0.305054)
			(stroke
				(width 0.1)
				(type default)
			)
			(layer "F.Fab")
		)
		(pad "1" smd circle
			(at -0.40005 0 180)
			(size 0 0)
			(layers "F.Cu" "F.Mask" "F.Paste")
			(net "CLK_100M_OCP_SFF_2_R_DP")
		)
		(pad "2" smd circle
			(at 0.40005 0 180)
			(size 0 0)
			(layers "F.Cu" "F.Mask" "F.Paste")
			(net "CLK_100M_OCP_SFF_2_DP")
		)
	)
	(footprint ""
		(layer "F.Cu")
		(at 386.849366 -394.643356)
		(property "Reference" "ME20"
			(at 0 0 0)
			(layer "F.SilkS")
			(hide yes)
			(effects
				(font
					(size 1.27 1.27)
				)
			)
		)
		(property "Value" ""
			(at 0 0 0)
			(layer "F.Fab")
			(effects
				(font
					(size 1.27 1.27)
				)
			)
		)
		(duplicate_pad_numbers_are_jumpers no)
	)
)
